(kicad_pcb
	(version 20260206)
	(generator "pcbnew")
	(generator_version "10.0")
	(general
		(thickness 1.6)
		(legacy_teardrops no)
	)
	(paper "A4")
	(title_block
		(title "12092022_DA0F0TMDCD0_F0T_Management_Board_D_brd_V3_OCP.brd")
		(comment 1 "Grand Teton / footprints 186-190 of 1440")
	)
	(layers
		(0 "F.Cu" signal "TOP")
		(4 "In1.Cu" signal "GND")
		(6 "In2.Cu" signal "IN1")
		(8 "In3.Cu" signal "GND1")
		(10 "In4.Cu" signal "IN2")
		(12 "In5.Cu" signal "VCC")
		(14 "In6.Cu" signal "VCC1")
		(16 "In7.Cu" signal "IN3")
		(18 "In8.Cu" signal "GND2")
		(20 "In9.Cu" signal "IN4")
		(22 "In10.Cu" signal "GND3")
		(2 "B.Cu" signal "BOTTOM")
		(9 "F.Adhes" user "F.Adhesive")
		(11 "B.Adhes" user "B.Adhesive")
		(13 "F.Paste" user "Package Geometry/Pastemask Top")
		(15 "B.Paste" user "Package Geometry/Pastemask Bottom")
		(5 "F.SilkS" user "Ref Des/Silkscreen Top")
		(7 "B.SilkS" user "Ref Des/Silkscreen Bottom")
		(1 "F.Mask" user "Board Geometry/Soldermask Top")
		(3 "B.Mask" user "Board Geometry/Soldermask Bottom")
		(17 "Dwgs.User" user "User.Drawings")
		(19 "Cmts.User" user "User.Comments")
		(21 "Eco1.User" user "User.Eco1")
		(23 "Eco2.User" user "User.Eco2")
		(25 "Edge.Cuts" user "Board Geometry/Outline")
		(27 "Margin" user)
		(31 "F.CrtYd" user "Package Geometry/Place Bound Top")
		(29 "B.CrtYd" user "Package Geometry/Place Bound Bottom")
		(35 "F.Fab" user "Ref Des/Assembly Top")
		(33 "B.Fab" user "Ref Des/Assembly Bottom")
	)
	(footprint ""
		(layer "F.Cu")
		(at 44.193968 -65.776094 -90)
		(property "Reference" "R186"
			(at 0 0 270)
			(layer "F.SilkS")
			(hide yes)
			(effects
				(font
					(size 1.27 1.27)
				)
			)
		)
		(property "Value" ""
			(at 0 0 270)
			(layer "F.Fab")
			(effects
				(font
					(size 1.27 1.27)
				)
			)
		)
		(duplicate_pad_numbers_are_jumpers no)
		(fp_line
			(start -0.7874 0.4064)
			(end -0.7874 -0.4064)
			(stroke
				(width 0.1524)
				(type default)
			)
			(layer "F.SilkS")
		)
		(fp_line
			(start 0.7874 0.4064)
			(end -0.7874 0.4064)
			(stroke
				(width 0.1524)
				(type default)
			)
			(layer "F.SilkS")
		)
		(fp_line
			(start -0.7874 -0.4064)
			(end 0.7874 -0.4064)
			(stroke
				(width 0.1524)
				(type default)
			)
			(layer "F.SilkS")
		)
		(fp_line
			(start 0.7874 -0.4064)
			(end 0.7874 0.4064)
			(stroke
				(width 0.1524)
				(type default)
			)
			(layer "F.SilkS")
		)
		(fp_line
			(start -0.67945 0.3048)
			(end -0.67945 -0.305054)
			(stroke
				(width 0.1)
				(type default)
			)
			(layer "F.Fab")
		)
		(fp_line
			(start -0.12065 0.3048)
			(end -0.67945 0.3048)
			(stroke
				(width 0.1)
				(type default)
			)
			(layer "F.Fab")
		)
		(fp_line
			(start 0.120396 0.3048)
			(end 0.120396 0.2794)
			(stroke
				(width 0.1)
				(type default)
			)
			(layer "F.Fab")
		)
		(fp_line
			(start 0.67945 0.3048)
			(end 0.120396 0.3048)
			(stroke
				(width 0.1)
				(type default)
			)
			(layer "F.Fab")
		)
		(fp_line
			(start -0.12065 0.2794)
			(end -0.12065 0.3048)
			(stroke
				(width 0.1)
				(type default)
			)
			(layer "F.Fab")
		)
		(fp_line
			(start 0.120396 0.2794)
			(end -0.12065 0.2794)
			(stroke
				(width 0.1)
				(type default)
			)
			(layer "F.Fab")
		)
		(fp_line
			(start -0.12065 -0.2794)
			(end 0.12065 -0.2794)
			(stroke
				(width 0.1)
				(type default)
			)
			(layer "F.Fab")
		)
		(fp_line
			(start 0.12065 -0.2794)
			(end 0.12065 -0.3048)
			(stroke
				(width 0.1)
				(type default)
			)
			(layer "F.Fab")
		)
		(fp_line
			(start 0.12065 -0.3048)
			(end 0.67945 -0.3048)
			(stroke
				(width 0.1)
				(type default)
			)
			(layer "F.Fab")
		)
		(fp_line
			(start 0.67945 -0.3048)
			(end 0.67945 0.3048)
			(stroke
				(width 0.1)
				(type default)
			)
			(layer "F.Fab")
		)
		(fp_line
			(start -0.67945 -0.305054)
			(end -0.12065 -0.305054)
			(stroke
				(width 0.1)
				(type default)
			)
			(layer "F.Fab")
		)
		(fp_line
			(start -0.12065 -0.305054)
			(end -0.12065 -0.2794)
			(stroke
				(width 0.1)
				(type default)
			)
			(layer "F.Fab")
		)
		(pad "1" smd circle
			(at -0.40005 0 270)
			(size 0 0)
			(layers "F.Cu" "F.Mask" "F.Paste")
			(net "I3C2_SPD_SCL")
		)
		(pad "2" smd circle
			(at 0.40005 0 270)
			(size 0 0)
			(layers "F.Cu" "F.Mask" "F.Paste")
			(net "I3C2_SCL_R")
		)
	)
	(footprint ""
		(layer "F.Cu")
		(at 51.832002 -63.953644 -90)
		(property "Reference" "R160"
			(at 0 0 270)
			(layer "F.SilkS")
			(hide yes)
			(effects
				(font
					(size 1.27 1.27)
				)
			)
		)
		(property "Value" ""
			(at 0 0 270)
			(layer "F.Fab")
			(effects
				(font
					(size 1.27 1.27)
				)
			)
		)
		(duplicate_pad_numbers_are_jumpers no)
		(fp_line
			(start -0.7874 0.4064)
			(end -0.7874 -0.4064)
			(stroke
				(width 0.1524)
				(type default)
			)
			(layer "F.SilkS")
		)
		(fp_line
			(start 0.7874 0.4064)
			(end -0.7874 0.4064)
			(stroke
				(width 0.1524)
				(type default)
			)
			(layer "F.SilkS")
		)
		(fp_line
			(start -0.7874 -0.4064)
			(end 0.7874 -0.4064)
			(stroke
				(width 0.1524)
				(type default)
			)
			(layer "F.SilkS")
		)
		(fp_line
			(start 0.7874 -0.4064)
			(end 0.7874 0.4064)
			(stroke
				(width 0.1524)
				(type default)
			)
			(layer "F.SilkS")
		)
		(fp_line
			(start -0.67945 0.3048)
			(end -0.67945 -0.305054)
			(stroke
				(width 0.1)
				(type default)
			)
			(layer "F.Fab")
		)
		(fp_line
			(start -0.12065 0.3048)
			(end -0.67945 0.3048)
			(stroke
				(width 0.1)
				(type default)
			)
			(layer "F.Fab")
		)
		(fp_line
			(start 0.120396 0.3048)
			(end 0.120396 0.2794)
			(stroke
				(width 0.1)
				(type default)
			)
			(layer "F.Fab")
		)
		(fp_line
			(start 0.67945 0.3048)
			(end 0.120396 0.3048)
			(stroke
				(width 0.1)
				(type default)
			)
			(layer "F.Fab")
		)
		(fp_line
			(start -0.12065 0.2794)
			(end -0.12065 0.3048)
			(stroke
				(width 0.1)
				(type default)
			)
			(layer "F.Fab")
		)
		(fp_line
			(start 0.120396 0.2794)
			(end -0.12065 0.2794)
			(stroke
				(width 0.1)
				(type default)
			)
			(layer "F.Fab")
		)
		(fp_line
			(start -0.12065 -0.2794)
			(end 0.12065 -0.2794)
			(stroke
				(width 0.1)
				(type default)
			)
			(layer "F.Fab")
		)
		(fp_line
			(start 0.12065 -0.2794)
			(end 0.12065 -0.3048)
			(stroke
				(width 0.1)
				(type default)
			)
			(layer "F.Fab")
		)
		(fp_line
			(start 0.12065 -0.3048)
			(end 0.67945 -0.3048)
			(stroke
				(width 0.1)
				(type default)
			)
			(layer "F.Fab")
		)
		(fp_line
			(start 0.67945 -0.3048)
			(end 0.67945 0.3048)
			(stroke
				(width 0.1)
				(type default)
			)
			(layer "F.Fab")
		)
		(fp_line
			(start -0.67945 -0.305054)
			(end -0.12065 -0.305054)
			(stroke
				(width 0.1)
				(type default)
			)
			(layer "F.Fab")
		)
		(fp_line
			(start -0.12065 -0.305054)
			(end -0.12065 -0.2794)
			(stroke
				(width 0.1)
				(type default)
			)
			(layer "F.Fab")
		)
		(pad "1" smd circle
			(at -0.40005 0 270)
			(size 0 0)
			(layers "F.Cu" "F.Mask" "F.Paste")
			(net "RST_RSMRST_N")
		)
		(pad "2" smd circle
			(at 0.40005 0 270)
			(size 0 0)
			(layers "F.Cu" "F.Mask" "F.Paste")
			(net "RST_RSMRST_R_N")
		)
	)
	(footprint ""
		(layer "F.Cu")
		(at 17.018 -102.743 90)
		(property "Reference" "R105"
			(at 0 0 90)
			(layer "F.SilkS")
			(hide yes)
			(effects
				(font
					(size 1.27 1.27)
				)
			)
		)
		(property "Value" ""
			(at 0 0 90)
			(layer "F.Fab")
			(effects
				(font
					(size 1.27 1.27)
				)
			)
		)
		(duplicate_pad_numbers_are_jumpers no)
		(fp_line
			(start 0.7874 -0.4064)
			(end 0.7874 0.4064)
			(stroke
				(width 0.1524)
				(type default)
			)
			(layer "F.SilkS")
		)
		(fp_line
			(start -0.7874 -0.4064)
			(end 0.7874 -0.4064)
			(stroke
				(width 0.1524)
				(type default)
			)
			(layer "F.SilkS")
		)
		(fp_line
			(start 0.7874 0.4064)
			(end -0.7874 0.4064)
			(stroke
				(width 0.1524)
				(type default)
			)
			(layer "F.SilkS")
		)
		(fp_line
			(start -0.7874 0.4064)
			(end -0.7874 -0.4064)
			(stroke
				(width 0.1524)
				(type default)
			)
			(layer "F.SilkS")
		)
		(fp_line
			(start -0.12065 -0.305054)
			(end -0.12065 -0.2794)
			(stroke
				(width 0.1)
				(type default)
			)
			(layer "F.Fab")
		)
		(fp_line
			(start -0.67945 -0.305054)
			(end -0.12065 -0.305054)
			(stroke
				(width 0.1)
				(type default)
			)
			(layer "F.Fab")
		)
		(fp_line
			(start 0.67945 -0.3048)
			(end 0.67945 0.3048)
			(stroke
				(width 0.1)
				(type default)
			)
			(layer "F.Fab")
		)
		(fp_line
			(start 0.12065 -0.3048)
			(end 0.67945 -0.3048)
			(stroke
				(width 0.1)
				(type default)
			)
			(layer "F.Fab")
		)
		(fp_line
			(start 0.12065 -0.2794)
			(end 0.12065 -0.3048)
			(stroke
				(width 0.1)
				(type default)
			)
			(layer "F.Fab")
		)
		(fp_line
			(start -0.12065 -0.2794)
			(end 0.12065 -0.2794)
			(stroke
				(width 0.1)
				(type default)
			)
			(layer "F.Fab")
		)
		(fp_line
			(start 0.120396 0.2794)
			(end -0.12065 0.2794)
			(stroke
				(width 0.1)
				(type default)
			)
			(layer "F.Fab")
		)
		(fp_line
			(start -0.12065 0.2794)
			(end -0.12065 0.3048)
			(stroke
				(width 0.1)
				(type default)
			)
			(layer "F.Fab")
		)
		(fp_line
			(start 0.67945 0.3048)
			(end 0.120396 0.3048)
			(stroke
				(width 0.1)
				(type default)
			)
			(layer "F.Fab")
		)
		(fp_line
			(start 0.120396 0.3048)
			(end 0.120396 0.2794)
			(stroke
				(width 0.1)
				(type default)
			)
			(layer "F.Fab")
		)
		(fp_line
			(start -0.12065 0.3048)
			(end -0.67945 0.3048)
			(stroke
				(width 0.1)
				(type default)
			)
			(layer "F.Fab")
		)
		(fp_line
			(start -0.67945 0.3048)
			(end -0.67945 -0.305054)
			(stroke
				(width 0.1)
				(type default)
			)
			(layer "F.Fab")
		)
		(pad "1" smd circle
			(at -0.40005 0 90)
			(size 0 0)
			(layers "F.Cu" "F.Mask" "F.Paste")
			(net "SMB_BMC_MM16_R4_SCL")
		)
		(pad "2" smd circle
			(at 0.40005 0 90)
			(size 0 0)
			(layers "F.Cu" "F.Mask" "F.Paste")
			(net "SMB_BMC_MM16_R5_SCL")
		)
	)
	(footprint ""
		(layer "F.Cu")
		(at 101.2825 -104.76484 -90)
		(property "Reference" "J12"
			(at -3.94716 -1.48717 90)
			(unlocked yes)
			(layer "F.SilkS")
			(effects
				(font
					(size 0.7874 0.5842)
					(thickness 0.1524)
				)
				(justify left)
			)
		)
		(property "Value" ""
			(at 0 0 270)
			(layer "F.Fab")
			(effects
				(font
					(size 1.27 1.27)
				)
			)
		)
		(duplicate_pad_numbers_are_jumpers no)
		(fp_line
			(start -1.2192 2.1082)
			(end -1.2192 -2.1082)
			(stroke
				(width 0.1524)
				(type default)
			)
			(layer "F.SilkS")
		)
		(fp_line
			(start 1.2192 2.1082)
			(end -1.2192 2.1082)
			(stroke
				(width 0.1524)
				(type default)
			)
			(layer "F.SilkS")
		)
		(fp_line
			(start 1.2192 0.466598)
			(end 1.2192 2.1082)
			(stroke
				(width 0.1524)
				(type default)
			)
			(layer "F.SilkS")
		)
		(fp_line
			(start -1.2192 -2.1082)
			(end 1.2192 -2.1082)
			(stroke
				(width 0.1524)
				(type default)
			)
			(layer "F.SilkS")
		)
		(fp_line
			(start 1.2192 -2.1082)
			(end 1.2192 -0.454406)
			(stroke
				(width 0.1524)
				(type default)
			)
			(layer "F.SilkS")
		)
		(pad "" np_thru_hole circle
			(at -2.8829 -1.27 180)
			(size 1.0414 1.0414)
			(drill 1.0414)
			(layers "*.Cu" "*.Mask")
			(clearance 0.381)
			(thermal_gap 0.381)
		)
		(pad "" np_thru_hole circle
			(at -2.8829 1.27 180)
			(size 1.0414 1.0414)
			(drill 1.0414)
			(layers "*.Cu" "*.Mask")
			(clearance 0.381)
			(thermal_gap 0.381)
		)
		(pad "" np_thru_hole circle
			(at 3.4671 -1.27 180)
			(size 1.0414 1.0414)
			(drill 1.0414)
			(layers "*.Cu" "*.Mask")
			(clearance 0.381)
			(thermal_gap 0.381)
		)
		(pad "" np_thru_hole circle
			(at 3.4671 1.27 180)
			(size 1.0414 1.0414)
			(drill 1.0414)
			(layers "*.Cu" "*.Mask")
			(clearance 0.381)
			(thermal_gap 0.381)
		)
		(pad "1" smd rect
			(at 0.8255 -0.249936 180)
			(size 0.3048 0.508)
			(layers "F.Cu" "F.Mask" "F.Paste")
			(net "85_5INCH_TOP_DP")
		)
		(pad "2" smd rect
			(at 0.8255 0.249936 180)
			(size 0.3048 0.508)
			(layers "F.Cu" "F.Mask" "F.Paste")
			(net "85_5INCH_TOP_DN")
		)
		(pad "3" smd circle
			(at 0 0 270)
			(size 0 0)
			(layers "F.Cu" "F.Mask" "F.Paste")
			(net "GND_P1")
		)
		(zone
			(layer "F.Cu")
			(hatch none 0.5)
			(connect_pads
				(clearance 0)
			)
			(min_thickness 0.25)
			(keepout
				(tracks not_allowed)
				(vias allowed)
				(pads allowed)
				(copperpour not_allowed)
				(footprints allowed)
			)
			(placement
				(enabled no)
				(sheetname "")
			)
			(fill
				(thermal_gap 0.5)
				(thermal_bridge_width 0.5)
				(island_removal_mode 0)
			)
			(polygon
				(pts
					(xy 101.83114 -103.64724) (xy 101.735636 -103.64724) (xy 101.735636 -104.24414) (xy 101.329236 -104.24414)
					(xy 101.329236 -103.64724) (xy 101.235764 -103.64724) (xy 101.235764 -104.24414) (xy 100.829364 -104.24414)
					(xy 100.829364 -103.64724) (xy 100.73386 -103.64724) (xy 100.73386 -104.34574) (xy 101.83114 -104.34574)
				)
			)
		)
		(zone
			(layers "F.Cu" "B.Cu" "In1.Cu" "In2.Cu" "In3.Cu" "In4.Cu" "In5.Cu" "In6.Cu"
				"In7.Cu" "In8.Cu" "In9.Cu" "In10.Cu"
			)
			(hatch none 0.5)
			(connect_pads
				(clearance 0)
			)
			(min_thickness 0.25)
			(keepout
				(tracks not_allowed)
				(vias allowed)
				(pads allowed)
				(copperpour not_allowed)
				(footprints allowed)
			)
			(placement
				(enabled no)
				(sheetname "")
			)
			(fill
				(thermal_gap 0.5)
				(thermal_bridge_width 0.5)
				(island_removal_mode 0)
			)
			(polygon
				(pts
					(arc
						(start 100.9396 -107.64774)
						(mid 99.0854 -107.64774)
						(end 100.9396 -107.64774)
					)
				)
			)
		)
		(zone
			(layers "F.Cu" "B.Cu" "In1.Cu" "In2.Cu" "In3.Cu" "In4.Cu" "In5.Cu" "In6.Cu"
				"In7.Cu" "In8.Cu" "In9.Cu" "In10.Cu"
			)
			(hatch none 0.5)
			(connect_pads
				(clearance 0)
			)
			(min_thickness 0.25)
			(keepout
				(tracks not_allowed)
				(vias allowed)
				(pads allowed)
				(copperpour not_allowed)
				(footprints allowed)
			)
			(placement
				(enabled no)
				(sheetname "")
			)
			(fill
				(thermal_gap 0.5)
				(thermal_bridge_width 0.5)
				(island_removal_mode 0)
			)
			(polygon
				(pts
					(arc
						(start 100.9396 -101.29774)
						(mid 99.0854 -101.29774)
						(end 100.9396 -101.29774)
					)
				)
			)
		)
		(zone
			(layers "F.Cu" "B.Cu" "In1.Cu" "In2.Cu" "In3.Cu" "In4.Cu" "In5.Cu" "In6.Cu"
				"In7.Cu" "In8.Cu" "In9.Cu" "In10.Cu"
			)
			(hatch none 0.5)
			(connect_pads
				(clearance 0)
			)
			(min_thickness 0.25)
			(keepout
				(tracks not_allowed)
				(vias allowed)
				(pads allowed)
				(copperpour not_allowed)
				(footprints allowed)
			)
			(placement
				(enabled no)
				(sheetname "")
			)
			(fill
				(thermal_gap 0.5)
				(thermal_bridge_width 0.5)
				(island_removal_mode 0)
			)
			(polygon
				(pts
					(arc
						(start 103.4796 -107.64774)
						(mid 101.6254 -107.64774)
						(end 103.4796 -107.64774)
					)
				)
			)
		)
		(zone
			(layers "F.Cu" "B.Cu" "In1.Cu" "In2.Cu" "In3.Cu" "In4.Cu" "In5.Cu" "In6.Cu"
				"In7.Cu" "In8.Cu" "In9.Cu" "In10.Cu"
			)
			(hatch none 0.5)
			(connect_pads
				(clearance 0)
			)
			(min_thickness 0.25)
			(keepout
				(tracks not_allowed)
				(vias allowed)
				(pads allowed)
				(copperpour not_allowed)
				(footprints allowed)
			)
			(placement
				(enabled no)
				(sheetname "")
			)
			(fill
				(thermal_gap 0.5)
				(thermal_bridge_width 0.5)
				(island_removal_mode 0)
			)
			(polygon
				(pts
					(arc
						(start 103.4796 -101.29774)
						(mid 101.6254 -101.29774)
						(end 103.4796 -101.29774)
					)
				)
			)
		)
	)
	(footprint ""
		(layer "F.Cu")
		(at 74.01052 -31.307786 90)
		(property "Reference" "D7"
			(at -3.672586 8.64235 90)
			(unlocked yes)
			(layer "F.SilkS")
			(effects
				(font
					(size 0.7874 0.5842)
					(thickness 0.1524)
				)
				(justify left)
			)
		)
		(property "Value" ""
			(at 0 0 90)
			(layer "F.Fab")
			(effects
				(font
					(size 1.27 1.27)
				)
			)
		)
		(duplicate_pad_numbers_are_jumpers no)
		(fp_line
			(start 1.778 -0.5588)
			(end 1.3208 -0.5588)
			(stroke
				(width 0.1524)
				(type default)
			)
			(layer "F.SilkS")
		)
		(fp_line
			(start 1.778 -0.5588)
			(end 1.778 0.5588)
			(stroke
				(width 0.1524)
				(type default)
			)
			(layer "F.SilkS")
		)
		(fp_line
			(start 1.4732 -0.5588)
			(end 1.4732 0.5588)
			(stroke
				(width 0.1524)
				(type default)
			)
			(layer "F.SilkS")
		)
		(fp_line
			(start 1.3208 -0.5588)
			(end 1.3208 0.5588)
			(stroke
				(width 0.1524)
				(type default)
			)
			(layer "F.SilkS")
		)
		(fp_line
			(start -1.3208 -0.5588)
			(end 1.3208 -0.5588)
			(stroke
				(width 0.1524)
				(type default)
			)
			(layer "F.SilkS")
		)
		(fp_line
			(start 1.778 0.5588)
			(end 1.3208 0.5588)
			(stroke
				(width 0.1524)
				(type default)
			)
			(layer "F.SilkS")
		)
		(fp_line
			(start 1.6256 0.5588)
			(end 1.6256 -0.5588)
			(stroke
				(width 0.1524)
				(type default)
			)
			(layer "F.SilkS")
		)
		(fp_line
			(start 1.3208 0.5588)
			(end -1.3208 0.5588)
			(stroke
				(width 0.1524)
				(type default)
			)
			(layer "F.SilkS")
		)
		(fp_line
			(start -1.3208 0.5588)
			(end -1.3208 -0.5588)
			(stroke
				(width 0.1524)
				(type default)
			)
			(layer "F.SilkS")
		)
		(fp_line
			(start 0.8001 -0.40005)
			(end 0.8001 0.40005)
			(stroke
				(width 0.1)
				(type default)
			)
			(layer "F.Fab")
		)
		(fp_line
			(start -0.8001 -0.40005)
			(end 0.8001 -0.40005)
			(stroke
				(width 0.1)
				(type default)
			)
			(layer "F.Fab")
		)
		(fp_line
			(start 0.8001 0.40005)
			(end -0.8001 0.40005)
			(stroke
				(width 0.1)
				(type default)
			)
			(layer "F.Fab")
		)
		(fp_line
			(start -0.8001 0.40005)
			(end -0.8001 -0.40005)
			(stroke
				(width 0.1)
				(type default)
			)
			(layer "F.Fab")
		)
		(fp_text user "+"
			(at -0.811276 -0.6985 270)
			(unlocked yes)
			(layer "F.SilkS")
			(effects
				(font
					(size 1.905 1.4224)
					(thickness 0.1524)
				)
				(justify left)
			)
		)
		(fp_text user "-"
			(at 1.6256 -0.22225 90)
			(unlocked yes)
			(layer "F.SilkS")
			(effects
				(font
					(size 1.905 1.4224)
					(thickness 0.1524)
				)
				(justify left)
			)
		)
		(fp_text user "-"
			(at 1.6256 -0.22225 90)
			(unlocked yes)
			(layer "F.Fab")
			(effects
				(font
					(size 1.905 1.4224)
					(thickness 0.1524)
				)
				(justify left)
			)
		)
		(fp_text user "+"
			(at -2.5654 -0.22225 90)
			(unlocked yes)
			(layer "F.Fab")
			(effects
				(font
					(size 1.905 1.4224)
					(thickness 0.1524)
				)
				(justify left)
			)
		)
		(pad "A" smd rect
			(at -0.750062 0 90)
			(size 0.8128 0.8128)
			(layers "F.Cu" "F.Mask" "F.Paste")
			(net "LED_POSTCODE_7_R")
		)
		(pad "C" smd rect
			(at 0.750062 0 90)
			(size 0.8128 0.8128)
			(layers "F.Cu" "F.Mask" "F.Paste")
			(net "GND")
		)
	)
)
